(kicad_pcb
	(version 20260206)
	(generator "pcbnew")
	(generator_version "10.0")
	(general
		(thickness 1.6)
		(legacy_teardrops no)
	)
	(paper "A4")
	(title_block
		(title "03242023_DA0F0TMBIJ0_F0T_Motherboard_J_brd_V01_OCP.brd")
		(comment 1 "Grand Teton / footprint 950 of 6105 (J107), pads 1-48 of 48")
	)
	(layers
		(0 "F.Cu" signal "TOP")
		(4 "In1.Cu" signal "GND")
		(6 "In2.Cu" signal "IN1")
		(8 "In3.Cu" signal "GND1")
		(10 "In4.Cu" signal "IN2")
		(12 "In5.Cu" signal "GND2")
		(14 "In6.Cu" signal "IN3")
		(16 "In7.Cu" signal "GND3")
		(18 "In8.Cu" signal "VCC")
		(20 "In9.Cu" signal "VCC1")
		(22 "In10.Cu" signal "GND4")
		(24 "In11.Cu" signal "IN4")
		(26 "In12.Cu" signal "GND5")
		(28 "In13.Cu" signal "IN5")
		(30 "In14.Cu" signal "GND6")
		(32 "In15.Cu" signal "IN6")
		(34 "In16.Cu" signal "GND7")
		(2 "B.Cu" signal "BOTTOM")
		(9 "F.Adhes" user "F.Adhesive")
		(11 "B.Adhes" user "B.Adhesive")
		(13 "F.Paste" user "Package Geometry/Pastemask Top")
		(15 "B.Paste" user "Package Geometry/Pastemask Bottom")
		(5 "F.SilkS" user "Ref Des/Silkscreen Top")
		(7 "B.SilkS" user "Ref Des/Silkscreen Bottom")
		(1 "F.Mask" user "Board Geometry/Soldermask Top")
		(3 "B.Mask" user "Board Geometry/Soldermask Bottom")
		(17 "Dwgs.User" user "User.Drawings")
		(19 "Cmts.User" user "User.Comments")
		(21 "Eco1.User" user "User.Eco1")
		(23 "Eco2.User" user "User.Eco2")
		(25 "Edge.Cuts" user "Board Geometry/Outline")
		(27 "Margin" user)
		(31 "F.CrtYd" user "Package Geometry/Place Bound Top")
		(29 "B.CrtYd" user "Package Geometry/Place Bound Bottom")
		(35 "F.Fab" user "Ref Des/Assembly Top")
		(33 "B.Fab" user "Ref Des/Assembly Bottom")
	)
	(footprint ""
		(layer "F.Cu")
		(at 331.650086 -440.489848)
		(property "Reference" "J107"
			(at 3.42392 23.088092 0)
			(unlocked yes)
			(layer "F.SilkS")
			(effects
				(font
					(size 0.7874 0.5842)
					(thickness 0.1524)
				)
				(justify left)
			)
		)
		(property "Value" ""
			(at 0 0 0)
			(layer "F.Fab")
			(effects
				(font
					(size 1.27 1.27)
				)
			)
		)
		(duplicate_pad_numbers_are_jumpers no)
		(pad "A1" thru_hole rect
			(at 0 0 180)
			(size 0.766318 0.766318)
			(drill 0.359918)
			(layers "*.Cu" "*.Mask")
			(remove_unused_layers no)
			(net "NC_J107_A1")
			(clearance 0.0508)
			(thermal_gap 0.0508)
			(padstack
				(mode front_inner_back)
				(layer "Inner"
					(shape circle)
					(size 0.766318 0.766318)
					(clearance 0.0508)
				)
				(layer "B.Cu"
					(shape rect)
					(size 0.766318 0.766318)
					(clearance 0.0508)
				)
			)
		)
		(pad "A2" thru_hole circle
			(at 1.999996 0.199898 180)
			(size 0.906272 0.906272)
			(drill 0.499872)
			(layers "*.Cu" "*.Mask")
			(remove_unused_layers no)
			(net "GND")
			(clearance 0.0508)
			(thermal_gap 0.0508)
		)
		(pad "A3" thru_hole circle
			(at 3.999992 0 180)
			(size 0.766318 0.766318)
			(drill 0.359918)
			(layers "*.Cu" "*.Mask")
			(remove_unused_layers no)
			(net "NC_J107_A3")
			(clearance 0.0508)
			(thermal_gap 0.0508)
		)
		(pad "A4" thru_hole circle
			(at 5.999988 0.199898 180)
			(size 0.906272 0.906272)
			(drill 0.499872)
			(layers "*.Cu" "*.Mask")
			(remove_unused_layers no)
			(net "GND")
			(clearance 0.0508)
			(thermal_gap 0.0508)
		)
		(pad "A5" thru_hole circle
			(at 7.999984 0 180)
			(size 0.766318 0.766318)
			(drill 0.359918)
			(layers "*.Cu" "*.Mask")
			(remove_unused_layers no)
			(net "NC_J107_A5")
			(clearance 0.0508)
			(thermal_gap 0.0508)
		)
		(pad "A6" thru_hole circle
			(at 9.99998 0.199898 180)
			(size 0.906272 0.906272)
			(drill 0.499872)
			(layers "*.Cu" "*.Mask")
			(remove_unused_layers no)
			(net "GND")
			(clearance 0.0508)
			(thermal_gap 0.0508)
		)
		(pad "A7" thru_hole circle
			(at 11.999976 0 180)
			(size 0.766318 0.766318)
			(drill 0.359918)
			(layers "*.Cu" "*.Mask")
			(remove_unused_layers no)
			(net "SWB_HSC_PWRGD")
			(clearance 0.0508)
			(thermal_gap 0.0508)
		)
		(pad "A8" thru_hole circle
			(at 13.999972 0.199898 180)
			(size 0.906272 0.906272)
			(drill 0.499872)
			(layers "*.Cu" "*.Mask")
			(remove_unused_layers no)
			(net "GND")
			(clearance 0.0508)
			(thermal_gap 0.0508)
		)
		(pad "B1" thru_hole circle
			(at 0 1.199896 180)
			(size 0.906272 0.906272)
			(drill 0.499872)
			(layers "*.Cu" "*.Mask")
			(remove_unused_layers no)
			(net "GND")
			(clearance 0.0508)
			(thermal_gap 0.0508)
		)
		(pad "B3" thru_hole circle
			(at 3.999992 1.199896 180)
			(size 0.906272 0.906272)
			(drill 0.499872)
			(layers "*.Cu" "*.Mask")
			(remove_unused_layers no)
			(net "GND")
			(clearance 0.0508)
			(thermal_gap 0.0508)
		)
		(pad "B5" thru_hole circle
			(at 7.999984 1.199896 180)
			(size 0.906272 0.906272)
			(drill 0.499872)
			(layers "*.Cu" "*.Mask")
			(remove_unused_layers no)
			(net "GND")
			(clearance 0.0508)
			(thermal_gap 0.0508)
		)
		(pad "B7" thru_hole circle
			(at 11.999976 1.199896 180)
			(size 0.906272 0.906272)
			(drill 0.499872)
			(layers "*.Cu" "*.Mask")
			(remove_unused_layers no)
			(net "GND")
			(clearance 0.0508)
			(thermal_gap 0.0508)
		)
		(pad "D2" thru_hole circle
			(at 1.999996 3.800094 180)
			(size 0.906272 0.906272)
			(drill 0.499872)
			(layers "*.Cu" "*.Mask")
			(remove_unused_layers no)
			(net "GND")
			(clearance 0.0508)
			(thermal_gap 0.0508)
		)
		(pad "D4" thru_hole circle
			(at 5.999988 3.800094 180)
			(size 0.906272 0.906272)
			(drill 0.499872)
			(layers "*.Cu" "*.Mask")
			(remove_unused_layers no)
			(net "GND")
			(clearance 0.0508)
			(thermal_gap 0.0508)
		)
		(pad "D6" thru_hole circle
			(at 9.99998 3.800094 180)
			(size 0.906272 0.906272)
			(drill 0.499872)
			(layers "*.Cu" "*.Mask")
			(remove_unused_layers no)
			(net "GND")
			(clearance 0.0508)
			(thermal_gap 0.0508)
		)
		(pad "D8" thru_hole circle
			(at 13.999972 3.800094 180)
			(size 0.906272 0.906272)
			(drill 0.499872)
			(layers "*.Cu" "*.Mask")
			(remove_unused_layers no)
			(net "GND")
			(clearance 0.0508)
			(thermal_gap 0.0508)
		)
		(pad "E1" thru_hole circle
			(at 0 4.800092 180)
			(size 0.906272 0.906272)
			(drill 0.499872)
			(layers "*.Cu" "*.Mask")
			(remove_unused_layers no)
			(net "GND")
			(clearance 0.0508)
			(thermal_gap 0.0508)
		)
		(pad "E3" thru_hole circle
			(at 3.999992 4.800092 180)
			(size 0.906272 0.906272)
			(drill 0.499872)
			(layers "*.Cu" "*.Mask")
			(remove_unused_layers no)
			(net "GND")
			(clearance 0.0508)
			(thermal_gap 0.0508)
		)
		(pad "E5" thru_hole circle
			(at 7.999984 4.800092 180)
			(size 0.906272 0.906272)
			(drill 0.499872)
			(layers "*.Cu" "*.Mask")
			(remove_unused_layers no)
			(net "GND")
			(clearance 0.0508)
			(thermal_gap 0.0508)
		)
		(pad "E7" thru_hole circle
			(at 11.999976 4.800092 180)
			(size 0.906272 0.906272)
			(drill 0.499872)
			(layers "*.Cu" "*.Mask")
			(remove_unused_layers no)
			(net "GND")
			(clearance 0.0508)
			(thermal_gap 0.0508)
		)
		(pad "G2" thru_hole circle
			(at 1.999996 7.400036 180)
			(size 0.906272 0.906272)
			(drill 0.499872)
			(layers "*.Cu" "*.Mask")
			(remove_unused_layers no)
			(net "GND")
			(clearance 0.0508)
			(thermal_gap 0.0508)
		)
		(pad "G4" thru_hole circle
			(at 5.999988 7.400036 180)
			(size 0.906272 0.906272)
			(drill 0.499872)
			(layers "*.Cu" "*.Mask")
			(remove_unused_layers no)
			(net "GND")
			(clearance 0.0508)
			(thermal_gap 0.0508)
		)
		(pad "G6" thru_hole circle
			(at 9.99998 7.400036 180)
			(size 0.906272 0.906272)
			(drill 0.499872)
			(layers "*.Cu" "*.Mask")
			(remove_unused_layers no)
			(net "GND")
			(clearance 0.0508)
			(thermal_gap 0.0508)
		)
		(pad "G8" thru_hole circle
			(at 13.999972 7.400036 180)
			(size 0.906272 0.906272)
			(drill 0.499872)
			(layers "*.Cu" "*.Mask")
			(remove_unused_layers no)
			(net "GND")
			(clearance 0.0508)
			(thermal_gap 0.0508)
		)
		(pad "H1" thru_hole circle
			(at 0 8.400034 180)
			(size 0.906272 0.906272)
			(drill 0.499872)
			(layers "*.Cu" "*.Mask")
			(remove_unused_layers no)
			(net "GND")
			(clearance 0.0508)
			(thermal_gap 0.0508)
		)
		(pad "H3" thru_hole circle
			(at 3.999992 8.400034 180)
			(size 0.906272 0.906272)
			(drill 0.499872)
			(layers "*.Cu" "*.Mask")
			(remove_unused_layers no)
			(net "GND")
			(clearance 0.0508)
			(thermal_gap 0.0508)
		)
		(pad "H5" thru_hole circle
			(at 7.999984 8.400034 180)
			(size 0.906272 0.906272)
			(drill 0.499872)
			(layers "*.Cu" "*.Mask")
			(remove_unused_layers no)
			(net "GND")
			(clearance 0.0508)
			(thermal_gap 0.0508)
		)
		(pad "H7" thru_hole circle
			(at 11.999976 8.400034 180)
			(size 0.906272 0.906272)
			(drill 0.499872)
			(layers "*.Cu" "*.Mask")
			(remove_unused_layers no)
			(net "GND")
			(clearance 0.0508)
			(thermal_gap 0.0508)
		)
		(pad "J2" thru_hole circle
			(at 1.999996 10.999978 180)
			(size 0.906272 0.906272)
			(drill 0.499872)
			(layers "*.Cu" "*.Mask")
			(remove_unused_layers no)
			(net "GND")
			(clearance 0.0508)
			(thermal_gap 0.0508)
		)
		(pad "J4" thru_hole circle
			(at 5.999988 10.999978 180)
			(size 0.906272 0.906272)
			(drill 0.499872)
			(layers "*.Cu" "*.Mask")
			(remove_unused_layers no)
			(net "GND")
			(clearance 0.0508)
			(thermal_gap 0.0508)
		)
		(pad "J6" thru_hole circle
			(at 9.99998 10.999978 180)
			(size 0.906272 0.906272)
			(drill 0.499872)
			(layers "*.Cu" "*.Mask")
			(remove_unused_layers no)
			(net "GND")
			(clearance 0.0508)
			(thermal_gap 0.0508)
		)
		(pad "J8" thru_hole circle
			(at 13.999972 10.999978 180)
			(size 0.906272 0.906272)
			(drill 0.499872)
			(layers "*.Cu" "*.Mask")
			(remove_unused_layers no)
			(net "GND")
			(clearance 0.0508)
			(thermal_gap 0.0508)
		)
		(pad "K1" thru_hole circle
			(at 0 11.999976 180)
			(size 0.906272 0.906272)
			(drill 0.499872)
			(layers "*.Cu" "*.Mask")
			(remove_unused_layers no)
			(net "GND")
			(clearance 0.0508)
			(thermal_gap 0.0508)
		)
		(pad "K3" thru_hole circle
			(at 3.999992 11.999976 180)
			(size 0.906272 0.906272)
			(drill 0.499872)
			(layers "*.Cu" "*.Mask")
			(remove_unused_layers no)
			(net "GND")
			(clearance 0.0508)
			(thermal_gap 0.0508)
		)
		(pad "K5" thru_hole circle
			(at 7.999984 11.999976 180)
			(size 0.906272 0.906272)
			(drill 0.499872)
			(layers "*.Cu" "*.Mask")
			(remove_unused_layers no)
			(net "GND")
			(clearance 0.0508)
			(thermal_gap 0.0508)
		)
		(pad "K7" thru_hole circle
			(at 11.999976 11.999976 180)
			(size 0.906272 0.906272)
			(drill 0.499872)
			(layers "*.Cu" "*.Mask")
			(remove_unused_layers no)
			(net "GND")
			(clearance 0.0508)
			(thermal_gap 0.0508)
		)
		(pad "M2" thru_hole circle
			(at 1.999996 14.59992 180)
			(size 0.906272 0.906272)
			(drill 0.499872)
			(layers "*.Cu" "*.Mask")
			(remove_unused_layers no)
			(net "GND")
			(clearance 0.0508)
			(thermal_gap 0.0508)
		)
		(pad "M4" thru_hole circle
			(at 5.999988 14.59992 180)
			(size 0.906272 0.906272)
			(drill 0.499872)
			(layers "*.Cu" "*.Mask")
			(remove_unused_layers no)
			(net "GND")
			(clearance 0.0508)
			(thermal_gap 0.0508)
		)
		(pad "M6" thru_hole circle
			(at 9.99998 14.59992 180)
			(size 0.906272 0.906272)
			(drill 0.499872)
			(layers "*.Cu" "*.Mask")
			(remove_unused_layers no)
			(net "GND")
			(clearance 0.0508)
			(thermal_gap 0.0508)
		)
		(pad "M8" thru_hole circle
			(at 13.999972 14.59992 180)
			(size 0.906272 0.906272)
			(drill 0.499872)
			(layers "*.Cu" "*.Mask")
			(remove_unused_layers no)
			(net "GND")
			(clearance 0.0508)
			(thermal_gap 0.0508)
		)
		(pad "N1" thru_hole circle
			(at 0 15.599918 180)
			(size 0.906272 0.906272)
			(drill 0.499872)
			(layers "*.Cu" "*.Mask")
			(remove_unused_layers no)
			(net "GND")
			(clearance 0.0508)
			(thermal_gap 0.0508)
		)
		(pad "N2" thru_hole circle
			(at 1.999996 15.80007 180)
			(size 0.766318 0.766318)
			(drill 0.359918)
			(layers "*.Cu" "*.Mask")
			(remove_unused_layers no)
			(net "PRSNT_CABLE_SWB_B2_N")
			(clearance 0.0508)
			(thermal_gap 0.0508)
		)
		(pad "N3" thru_hole circle
			(at 3.999992 15.599918 180)
			(size 0.906272 0.906272)
			(drill 0.499872)
			(layers "*.Cu" "*.Mask")
			(remove_unused_layers no)
			(net "GND")
			(clearance 0.0508)
			(thermal_gap 0.0508)
		)
		(pad "N4" thru_hole circle
			(at 5.999988 15.80007 180)
			(size 0.766318 0.766318)
			(drill 0.359918)
			(layers "*.Cu" "*.Mask")
			(remove_unused_layers no)
			(net "NC_J107_N4")
			(clearance 0.0508)
			(thermal_gap 0.0508)
		)
		(pad "N5" thru_hole circle
			(at 7.999984 15.599918 180)
			(size 0.906272 0.906272)
			(drill 0.499872)
			(layers "*.Cu" "*.Mask")
			(remove_unused_layers no)
			(net "GND")
			(clearance 0.0508)
			(thermal_gap 0.0508)
		)
		(pad "N6" thru_hole circle
			(at 9.99998 15.80007 180)
			(size 0.766318 0.766318)
			(drill 0.359918)
			(layers "*.Cu" "*.Mask")
			(remove_unused_layers no)
			(net "NC_J107_N6")
			(clearance 0.0508)
			(thermal_gap 0.0508)
		)
		(pad "N7" thru_hole circle
			(at 11.999976 15.599918 180)
			(size 0.906272 0.906272)
			(drill 0.499872)
			(layers "*.Cu" "*.Mask")
			(remove_unused_layers no)
			(net "GND")
			(clearance 0.0508)
			(thermal_gap 0.0508)
		)
		(pad "N8" thru_hole circle
			(at 13.999972 15.80007 180)
			(size 0.766318 0.766318)
			(drill 0.359918)
			(layers "*.Cu" "*.Mask")
			(remove_unused_layers no)
			(net "SWB_HSC_EN_BUF")
			(clearance 0.0508)
			(thermal_gap 0.0508)
		)
	)
)
